FILE_TYPE = CONNECTIVITY;
{Allegro Design Entry HDL 17.4-2019 S026 (4007227) 1/17/2022}
"PAGE_NUMBER" = 432;
0"NC";
1"GND\g";
2"GND\g";
3"GND\g";
4"GND\g";
5"SMB_RT_CPU0_P3_ROM_R_SDA";
6"SMB_RT_CPU0_P3_ROM_SDA";
7"SMB_RT_CPU0_P3_ROM_R_SCL";
8"SMB_RT_CPU0_P3_ROM_SCL";
9"P1V8_CPU0_RT_1D\g";
10"U17_E2";
%"Q_RES"
"2","(-4175,5400)","0","pure_quanta","I18";
;
LOCATION"R1127"
$SEC"1"
CDS_SEC"1"
PACK_TYPE"0201LF"
MATERIAL"CHIP"
WATTAGE"1/20W"
TOLERANCE"1%"
VALUE"1K"
CDS_LIB"pure_quanta"
PART_NUMBER"CS21001FE07";
"A"
$PN"1"10;
"B"
$PN"2"2;
%"UNIVERSAL_GND"
"1","(-4325,5325)","0","pure_quanta_power","I19";
;
CDS_LIB"pure_quanta_power"
HDL_POWER"GND";
"A"1;
%"UNIVERSAL_GND"
"1","(-4175,4975)","0","pure_quanta_power","I20";
;
CDS_LIB"pure_quanta_power"
HDL_POWER"GND";
"A"2;
%"UNIVERSAL_GND"
"1","(-5275,5650)","7","pure_quanta_power","I21";
;
CDS_LIB"pure_quanta_power"
HDL_POWER"GND";
"A"3;
%"P1V0"
"1","(-5275,6475)","0","pure_quanta_power","I22";
;
HDL_POWER"P1V8_CPU0_RT_1D"
CDS_LIB"pure_quanta_power";
"A"9;
%"Q_CAP"
"1","(-5575,6125)","0","pure_quanta","I23";
;
LOCATION"C1057"
$SEC"1"
CDS_SEC"1"
VOLTAGE"10V"
TOLERANCE"10%"
MATERIAL"X7S"
PACK_TYPE"C0201"
VALUE"0.1UF"
CDS_LIB"pure_quanta"
PART_NUMBER"CH4102K6E00";
"B"
$PN"2"4;
"A"
$PN"1"9;
%"UNIVERSAL_GND"
"1","(-5575,5850)","0","pure_quanta_power","I24";
;
CDS_LIB"pure_quanta_power"
HDL_POWER"GND";
"A"4;
%"Q_RES"
"1","(-6275,5600)","0","pure_quanta","I3";
;
LOCATION"R687"
$SEC"1"
CDS_SEC"1"
MATERIAL"CHIP"
WATTAGE"1/20W"
PACK_TYPE"0201LF"
VALUE"33.2"
TOLERANCE"1%"
CDS_LIB"pure_quanta"
PART_NUMBER"CS03321FE09";
"B"
$PN"2"8;
"A"
$PN"1"7;
%"Q_RES"
"1","(-6275,5550)","0","pure_quanta","I4";
;
LOCATION"R688"
$SEC"1"
CDS_SEC"1"
MATERIAL"CHIP"
CDS_LIB"pure_quanta"
WATTAGE"1/20W"
PACK_TYPE"0201LF"
VALUE"33.2"
TOLERANCE"1%"
PART_NUMBER"CS03321FE09";
"B"
$PN"2"6;
"A"
$PN"1"5;
%"M24M02DRMN6TP"
"1","(-4850,5625)","0","pure_quanta","I5";
;
LOCATION"U17"
$SEC"1"
CDS_SEC"1"
PART_TYPE"SMLF"
MATERIAL"IC"
VALUE"M24M02-DRMN6TP"
CDS_LIB"pure_quanta"
CDS_LMAN_SYM_OUTLINE"-175,125,175,-125"
NEEDS_NO_SIZE"TRUE"
PART_NUMBER"AKE33Z00600";
"DU1"
$PN"1"0;
"DU2"
$PN"2"0;
"E2"
$PN"3"10;
"VSS"
$PN"4"1;
"SDA"
$PN"5"6;
"SCL"
$PN"6"8;
"WC_N \B"
$PN"7"3;
"VCC"
$PN"8"9;
END.
